(kicad_pcb
	(version 20260206)
	(generator "pcbnew")
	(generator_version "10.0")
	(general
		(thickness 1.6)
		(legacy_teardrops no)
	)
	(paper "A4")
	(title_block
		(title "04192023_DAF0TMB3IC0_F0TG_MB_C_brd_V02_OCP.brd")
		(comment 1 "Grand Teton / footprints 49-56 of 8354")
	)
	(layers
		(0 "F.Cu" signal "TOP")
		(4 "In1.Cu" signal "GND")
		(6 "In2.Cu" signal "IN1")
		(8 "In3.Cu" signal "GND1")
		(10 "In4.Cu" signal "IN2")
		(12 "In5.Cu" signal "GND2")
		(14 "In6.Cu" signal "IN3")
		(16 "In7.Cu" signal "GND3")
		(18 "In8.Cu" signal "VCC")
		(20 "In9.Cu" signal "VCC1")
		(22 "In10.Cu" signal "GND4")
		(24 "In11.Cu" signal "IN4")
		(26 "In12.Cu" signal "GND5")
		(28 "In13.Cu" signal "IN5")
		(30 "In14.Cu" signal "GND6")
		(32 "In15.Cu" signal "IN6")
		(34 "In16.Cu" signal "GND7")
		(2 "B.Cu" signal "BOTTOM")
		(9 "F.Adhes" user "F.Adhesive")
		(11 "B.Adhes" user "B.Adhesive")
		(13 "F.Paste" user "Package Geometry/Pastemask Top")
		(15 "B.Paste" user "Package Geometry/Pastemask Bottom")
		(5 "F.SilkS" user "Ref Des/Silkscreen Top")
		(7 "B.SilkS" user "Ref Des/Silkscreen Bottom")
		(1 "F.Mask" user "Board Geometry/Soldermask Top")
		(3 "B.Mask" user "Board Geometry/Soldermask Bottom")
		(17 "Dwgs.User" user "User.Drawings")
		(19 "Cmts.User" user "User.Comments")
		(21 "Eco1.User" user "User.Eco1")
		(23 "Eco2.User" user "User.Eco2")
		(25 "Edge.Cuts" user "Board Geometry/Outline")
		(27 "Margin" user)
		(31 "F.CrtYd" user "Package Geometry/Place Bound Top")
		(29 "B.CrtYd" user "Package Geometry/Place Bound Bottom")
		(35 "F.Fab" user "Ref Des/Assembly Top")
		(33 "B.Fab" user "Ref Des/Assembly Bottom")
	)
	(footprint ""
		(layer "F.Cu")
		(at 196.088 -133.568948 -90)
		(property "Reference" "R6085"
			(at 0 0 270)
			(layer "F.SilkS")
			(hide yes)
			(effects
				(font
					(size 1.27 1.27)
				)
			)
		)
		(property "Value" ""
			(at 0 0 270)
			(layer "F.Fab")
			(effects
				(font
					(size 1.27 1.27)
				)
			)
		)
		(duplicate_pad_numbers_are_jumpers no)
		(fp_line
			(start -0.7874 0.4064)
			(end -0.7874 -0.4064)
			(stroke
				(width 0.1524)
				(type default)
			)
			(layer "F.SilkS")
		)
		(fp_line
			(start 0.7874 0.4064)
			(end -0.7874 0.4064)
			(stroke
				(width 0.1524)
				(type default)
			)
			(layer "F.SilkS")
		)
		(fp_line
			(start -0.7874 -0.4064)
			(end 0.7874 -0.4064)
			(stroke
				(width 0.1524)
				(type default)
			)
			(layer "F.SilkS")
		)
		(fp_line
			(start 0.7874 -0.4064)
			(end 0.7874 0.4064)
			(stroke
				(width 0.1524)
				(type default)
			)
			(layer "F.SilkS")
		)
		(fp_line
			(start -0.67945 0.3048)
			(end -0.67945 -0.305054)
			(stroke
				(width 0.1)
				(type default)
			)
			(layer "F.Fab")
		)
		(fp_line
			(start -0.12065 0.3048)
			(end -0.67945 0.3048)
			(stroke
				(width 0.1)
				(type default)
			)
			(layer "F.Fab")
		)
		(fp_line
			(start 0.120396 0.3048)
			(end 0.120396 0.2794)
			(stroke
				(width 0.1)
				(type default)
			)
			(layer "F.Fab")
		)
		(fp_line
			(start 0.67945 0.3048)
			(end 0.120396 0.3048)
			(stroke
				(width 0.1)
				(type default)
			)
			(layer "F.Fab")
		)
		(fp_line
			(start -0.12065 0.2794)
			(end -0.12065 0.3048)
			(stroke
				(width 0.1)
				(type default)
			)
			(layer "F.Fab")
		)
		(fp_line
			(start 0.120396 0.2794)
			(end -0.12065 0.2794)
			(stroke
				(width 0.1)
				(type default)
			)
			(layer "F.Fab")
		)
		(fp_line
			(start -0.12065 -0.2794)
			(end 0.12065 -0.2794)
			(stroke
				(width 0.1)
				(type default)
			)
			(layer "F.Fab")
		)
		(fp_line
			(start 0.12065 -0.2794)
			(end 0.12065 -0.3048)
			(stroke
				(width 0.1)
				(type default)
			)
			(layer "F.Fab")
		)
		(fp_line
			(start 0.12065 -0.3048)
			(end 0.67945 -0.3048)
			(stroke
				(width 0.1)
				(type default)
			)
			(layer "F.Fab")
		)
		(fp_line
			(start 0.67945 -0.3048)
			(end 0.67945 0.3048)
			(stroke
				(width 0.1)
				(type default)
			)
			(layer "F.Fab")
		)
		(fp_line
			(start -0.67945 -0.305054)
			(end -0.12065 -0.305054)
			(stroke
				(width 0.1)
				(type default)
			)
			(layer "F.Fab")
		)
		(fp_line
			(start -0.12065 -0.305054)
			(end -0.12065 -0.2794)
			(stroke
				(width 0.1)
				(type default)
			)
			(layer "F.Fab")
		)
		(pad "1" smd circle
			(at -0.40005 0 270)
			(size 0 0)
			(layers "F.Cu" "F.Mask" "F.Paste")
			(net "P3V3_AUX")
		)
		(pad "2" smd circle
			(at 0.40005 0 270)
			(size 0 0)
			(layers "F.Cu" "F.Mask" "F.Paste")
			(net "PU_SPI_PLD_CS_N")
		)
	)
	(footprint ""
		(layer "F.Cu")
		(at 115.024408 -71.962772 180)
		(property "Reference" "PC6023"
			(at 0 0 180)
			(layer "F.SilkS")
			(hide yes)
			(effects
				(font
					(size 1.27 1.27)
				)
			)
		)
		(property "Value" ""
			(at 0 0 180)
			(layer "F.Fab")
			(effects
				(font
					(size 1.27 1.27)
				)
			)
		)
		(duplicate_pad_numbers_are_jumpers no)
		(fp_line
			(start 0.7874 0.4064)
			(end -0.7874 0.4064)
			(stroke
				(width 0.1524)
				(type default)
			)
			(layer "F.SilkS")
		)
		(fp_line
			(start 0.7874 -0.4064)
			(end 0.7874 0.4064)
			(stroke
				(width 0.1524)
				(type default)
			)
			(layer "F.SilkS")
		)
		(fp_line
			(start -0.7874 0.4064)
			(end -0.7874 -0.4064)
			(stroke
				(width 0.1524)
				(type default)
			)
			(layer "F.SilkS")
		)
		(fp_line
			(start -0.7874 -0.4064)
			(end 0.7874 -0.4064)
			(stroke
				(width 0.1524)
				(type default)
			)
			(layer "F.SilkS")
		)
		(fp_line
			(start 0.67945 0.3048)
			(end 0.120396 0.3048)
			(stroke
				(width 0.1)
				(type default)
			)
			(layer "F.Fab")
		)
		(fp_line
			(start 0.67945 -0.3048)
			(end 0.67945 0.3048)
			(stroke
				(width 0.1)
				(type default)
			)
			(layer "F.Fab")
		)
		(fp_line
			(start 0.12065 -0.2794)
			(end 0.12065 -0.3048)
			(stroke
				(width 0.1)
				(type default)
			)
			(layer "F.Fab")
		)
		(fp_line
			(start 0.12065 -0.3048)
			(end 0.67945 -0.3048)
			(stroke
				(width 0.1)
				(type default)
			)
			(layer "F.Fab")
		)
		(fp_line
			(start 0.120396 0.3048)
			(end 0.120396 0.2794)
			(stroke
				(width 0.1)
				(type default)
			)
			(layer "F.Fab")
		)
		(fp_line
			(start 0.120396 0.2794)
			(end -0.12065 0.2794)
			(stroke
				(width 0.1)
				(type default)
			)
			(layer "F.Fab")
		)
		(fp_line
			(start -0.12065 0.3048)
			(end -0.67945 0.3048)
			(stroke
				(width 0.1)
				(type default)
			)
			(layer "F.Fab")
		)
		(fp_line
			(start -0.12065 0.2794)
			(end -0.12065 0.3048)
			(stroke
				(width 0.1)
				(type default)
			)
			(layer "F.Fab")
		)
		(fp_line
			(start -0.12065 -0.2794)
			(end 0.12065 -0.2794)
			(stroke
				(width 0.1)
				(type default)
			)
			(layer "F.Fab")
		)
		(fp_line
			(start -0.12065 -0.305054)
			(end -0.12065 -0.2794)
			(stroke
				(width 0.1)
				(type default)
			)
			(layer "F.Fab")
		)
		(fp_line
			(start -0.67945 0.3048)
			(end -0.67945 -0.305054)
			(stroke
				(width 0.1)
				(type default)
			)
			(layer "F.Fab")
		)
		(fp_line
			(start -0.67945 -0.305054)
			(end -0.12065 -0.305054)
			(stroke
				(width 0.1)
				(type default)
			)
			(layer "F.Fab")
		)
		(pad "1" smd circle
			(at -0.40005 0 180)
			(size 0 0)
			(layers "F.Cu" "F.Mask" "F.Paste")
			(net "P12V_AUX")
		)
		(pad "2" smd circle
			(at 0.40005 0 180)
			(size 0 0)
			(layers "F.Cu" "F.Mask" "F.Paste")
			(net "GND")
		)
	)
	(footprint ""
		(layer "F.Cu")
		(at 75.49515 -376.85726 180)
		(property "Reference" "C738"
			(at 0 0 180)
			(layer "F.SilkS")
			(hide yes)
			(effects
				(font
					(size 1.27 1.27)
				)
			)
		)
		(property "Value" ""
			(at 0 0 180)
			(layer "F.Fab")
			(effects
				(font
					(size 1.27 1.27)
				)
			)
		)
		(duplicate_pad_numbers_are_jumpers no)
		(fp_line
			(start 0.299974 0.150114)
			(end -0.299974 0.150114)
			(stroke
				(width 0.1)
				(type default)
			)
			(layer "F.Fab")
		)
		(fp_line
			(start 0.299974 -0.150114)
			(end 0.299974 0.150114)
			(stroke
				(width 0.1)
				(type default)
			)
			(layer "F.Fab")
		)
		(fp_line
			(start -0.299974 0.150114)
			(end -0.299974 -0.150114)
			(stroke
				(width 0.1)
				(type default)
			)
			(layer "F.Fab")
		)
		(fp_line
			(start -0.299974 -0.150114)
			(end 0.299974 -0.150114)
			(stroke
				(width 0.1)
				(type default)
			)
			(layer "F.Fab")
		)
		(pad "1" smd rect
			(at -0.2667 0 180)
			(size 0.3048 0.381)
			(layers "F.Cu" "F.Mask" "F.Paste")
			(net "P5E_CPU1_P1_TX_C_DN<1>")
		)
		(pad "2" smd rect
			(at 0.2667 0 180)
			(size 0.3048 0.381)
			(layers "F.Cu" "F.Mask" "F.Paste")
			(net "P5E_CPU1_P1_TX_DN<1>")
		)
	)
	(footprint ""
		(layer "F.Cu")
		(at 441.050172 -32.173418 90)
		(property "Reference" "PC2155"
			(at 0 0 90)
			(layer "F.SilkS")
			(hide yes)
			(effects
				(font
					(size 1.27 1.27)
				)
			)
		)
		(property "Value" ""
			(at 0 0 90)
			(layer "F.Fab")
			(effects
				(font
					(size 1.27 1.27)
				)
			)
		)
		(duplicate_pad_numbers_are_jumpers no)
		(fp_line
			(start 0.7874 -0.4064)
			(end 0.7874 0.4064)
			(stroke
				(width 0.1524)
				(type default)
			)
			(layer "F.SilkS")
		)
		(fp_line
			(start -0.7874 -0.4064)
			(end 0.7874 -0.4064)
			(stroke
				(width 0.1524)
				(type default)
			)
			(layer "F.SilkS")
		)
		(fp_line
			(start 0.7874 0.4064)
			(end -0.7874 0.4064)
			(stroke
				(width 0.1524)
				(type default)
			)
			(layer "F.SilkS")
		)
		(fp_line
			(start -0.7874 0.4064)
			(end -0.7874 -0.4064)
			(stroke
				(width 0.1524)
				(type default)
			)
			(layer "F.SilkS")
		)
		(fp_line
			(start -0.12065 -0.305054)
			(end -0.12065 -0.2794)
			(stroke
				(width 0.1)
				(type default)
			)
			(layer "F.Fab")
		)
		(fp_line
			(start -0.67945 -0.305054)
			(end -0.12065 -0.305054)
			(stroke
				(width 0.1)
				(type default)
			)
			(layer "F.Fab")
		)
		(fp_line
			(start 0.67945 -0.3048)
			(end 0.67945 0.3048)
			(stroke
				(width 0.1)
				(type default)
			)
			(layer "F.Fab")
		)
		(fp_line
			(start 0.12065 -0.3048)
			(end 0.67945 -0.3048)
			(stroke
				(width 0.1)
				(type default)
			)
			(layer "F.Fab")
		)
		(fp_line
			(start 0.12065 -0.2794)
			(end 0.12065 -0.3048)
			(stroke
				(width 0.1)
				(type default)
			)
			(layer "F.Fab")
		)
		(fp_line
			(start -0.12065 -0.2794)
			(end 0.12065 -0.2794)
			(stroke
				(width 0.1)
				(type default)
			)
			(layer "F.Fab")
		)
		(fp_line
			(start 0.120396 0.2794)
			(end -0.12065 0.2794)
			(stroke
				(width 0.1)
				(type default)
			)
			(layer "F.Fab")
		)
		(fp_line
			(start -0.12065 0.2794)
			(end -0.12065 0.3048)
			(stroke
				(width 0.1)
				(type default)
			)
			(layer "F.Fab")
		)
		(fp_line
			(start 0.67945 0.3048)
			(end 0.120396 0.3048)
			(stroke
				(width 0.1)
				(type default)
			)
			(layer "F.Fab")
		)
		(fp_line
			(start 0.120396 0.3048)
			(end 0.120396 0.2794)
			(stroke
				(width 0.1)
				(type default)
			)
			(layer "F.Fab")
		)
		(fp_line
			(start -0.12065 0.3048)
			(end -0.67945 0.3048)
			(stroke
				(width 0.1)
				(type default)
			)
			(layer "F.Fab")
		)
		(fp_line
			(start -0.67945 0.3048)
			(end -0.67945 -0.305054)
			(stroke
				(width 0.1)
				(type default)
			)
			(layer "F.Fab")
		)
		(pad "1" smd circle
			(at -0.40005 0 90)
			(size 0 0)
			(layers "F.Cu" "F.Mask" "F.Paste")
			(net "P12V_OCP_SS_1")
		)
		(pad "2" smd circle
			(at 0.40005 0 90)
			(size 0 0)
			(layers "F.Cu" "F.Mask" "F.Paste")
			(net "GND")
		)
	)
	(footprint ""
		(layer "F.Cu")
		(at 194.2211 -400.998182 180)
		(property "Reference" "PR3918"
			(at 0 0 180)
			(layer "F.SilkS")
			(hide yes)
			(effects
				(font
					(size 1.27 1.27)
				)
			)
		)
		(property "Value" ""
			(at 0 0 180)
			(layer "F.Fab")
			(effects
				(font
					(size 1.27 1.27)
				)
			)
		)
		(duplicate_pad_numbers_are_jumpers no)
		(fp_line
			(start 0.7874 0.4064)
			(end -0.7874 0.4064)
			(stroke
				(width 0.1524)
				(type default)
			)
			(layer "F.SilkS")
		)
		(fp_line
			(start 0.7874 -0.4064)
			(end 0.7874 0.4064)
			(stroke
				(width 0.1524)
				(type default)
			)
			(layer "F.SilkS")
		)
		(fp_line
			(start -0.7874 0.4064)
			(end -0.7874 -0.4064)
			(stroke
				(width 0.1524)
				(type default)
			)
			(layer "F.SilkS")
		)
		(fp_line
			(start -0.7874 -0.4064)
			(end 0.7874 -0.4064)
			(stroke
				(width 0.1524)
				(type default)
			)
			(layer "F.SilkS")
		)
		(fp_line
			(start 0.67945 0.3048)
			(end 0.120396 0.3048)
			(stroke
				(width 0.1)
				(type default)
			)
			(layer "F.Fab")
		)
		(fp_line
			(start 0.67945 -0.3048)
			(end 0.67945 0.3048)
			(stroke
				(width 0.1)
				(type default)
			)
			(layer "F.Fab")
		)
		(fp_line
			(start 0.12065 -0.2794)
			(end 0.12065 -0.3048)
			(stroke
				(width 0.1)
				(type default)
			)
			(layer "F.Fab")
		)
		(fp_line
			(start 0.12065 -0.3048)
			(end 0.67945 -0.3048)
			(stroke
				(width 0.1)
				(type default)
			)
			(layer "F.Fab")
		)
		(fp_line
			(start 0.120396 0.3048)
			(end 0.120396 0.2794)
			(stroke
				(width 0.1)
				(type default)
			)
			(layer "F.Fab")
		)
		(fp_line
			(start 0.120396 0.2794)
			(end -0.12065 0.2794)
			(stroke
				(width 0.1)
				(type default)
			)
			(layer "F.Fab")
		)
		(fp_line
			(start -0.12065 0.3048)
			(end -0.67945 0.3048)
			(stroke
				(width 0.1)
				(type default)
			)
			(layer "F.Fab")
		)
		(fp_line
			(start -0.12065 0.2794)
			(end -0.12065 0.3048)
			(stroke
				(width 0.1)
				(type default)
			)
			(layer "F.Fab")
		)
		(fp_line
			(start -0.12065 -0.2794)
			(end 0.12065 -0.2794)
			(stroke
				(width 0.1)
				(type default)
			)
			(layer "F.Fab")
		)
		(fp_line
			(start -0.12065 -0.305054)
			(end -0.12065 -0.2794)
			(stroke
				(width 0.1)
				(type default)
			)
			(layer "F.Fab")
		)
		(fp_line
			(start -0.67945 0.3048)
			(end -0.67945 -0.305054)
			(stroke
				(width 0.1)
				(type default)
			)
			(layer "F.Fab")
		)
		(fp_line
			(start -0.67945 -0.305054)
			(end -0.12065 -0.305054)
			(stroke
				(width 0.1)
				(type default)
			)
			(layer "F.Fab")
		)
		(pad "1" smd circle
			(at -0.40005 0 180)
			(size 0 0)
			(layers "F.Cu" "F.Mask" "F.Paste")
			(net "HSC_IMON")
		)
		(pad "2" smd circle
			(at 0.40005 0 180)
			(size 0 0)
			(layers "F.Cu" "F.Mask" "F.Paste")
			(net "AGND_HSC")
		)
	)
	(footprint ""
		(layer "F.Cu")
		(at 328.694542 -395.1732 90)
		(property "Reference" "R967"
			(at 0 0 90)
			(layer "F.SilkS")
			(hide yes)
			(effects
				(font
					(size 1.27 1.27)
				)
			)
		)
		(property "Value" ""
			(at 0 0 90)
			(layer "F.Fab")
			(effects
				(font
					(size 1.27 1.27)
				)
			)
		)
		(duplicate_pad_numbers_are_jumpers no)
		(fp_line
			(start 0.32512 -0.175006)
			(end 0.32512 0.175006)
			(stroke
				(width 0.1)
				(type default)
			)
			(layer "F.Fab")
		)
		(fp_line
			(start -0.32512 -0.175006)
			(end 0.32512 -0.175006)
			(stroke
				(width 0.1)
				(type default)
			)
			(layer "F.Fab")
		)
		(fp_line
			(start 0.32512 0.175006)
			(end -0.32512 0.175006)
			(stroke
				(width 0.1)
				(type default)
			)
			(layer "F.Fab")
		)
		(fp_line
			(start -0.32512 0.175006)
			(end -0.32512 -0.175006)
			(stroke
				(width 0.1)
				(type default)
			)
			(layer "F.Fab")
		)
		(pad "1" smd rect
			(at -0.2667 0 90)
			(size 0.3048 0.381)
			(layers "F.Cu" "F.Mask" "F.Paste")
			(net "RT_CPU0_P0_ADDR2")
		)
		(pad "2" smd rect
			(at 0.2667 0 270)
			(size 0.3048 0.381)
			(layers "F.Cu" "F.Mask" "F.Paste")
			(net "GND")
		)
	)
	(footprint ""
		(layer "F.Cu")
		(at 69.741034 -380.385828)
		(property "Reference" "C806"
			(at 0 0 0)
			(layer "F.SilkS")
			(hide yes)
			(effects
				(font
					(size 1.27 1.27)
				)
			)
		)
		(property "Value" ""
			(at 0 0 0)
			(layer "F.Fab")
			(effects
				(font
					(size 1.27 1.27)
				)
			)
		)
		(duplicate_pad_numbers_are_jumpers no)
		(fp_line
			(start -0.299974 -0.150114)
			(end 0.299974 -0.150114)
			(stroke
				(width 0.1)
				(type default)
			)
			(layer "F.Fab")
		)
		(fp_line
			(start -0.299974 0.150114)
			(end -0.299974 -0.150114)
			(stroke
				(width 0.1)
				(type default)
			)
			(layer "F.Fab")
		)
		(fp_line
			(start 0.299974 -0.150114)
			(end 0.299974 0.150114)
			(stroke
				(width 0.1)
				(type default)
			)
			(layer "F.Fab")
		)
		(fp_line
			(start 0.299974 0.150114)
			(end -0.299974 0.150114)
			(stroke
				(width 0.1)
				(type default)
			)
			(layer "F.Fab")
		)
		(pad "1" smd rect
			(at -0.2667 0)
			(size 0.3048 0.381)
			(layers "F.Cu" "F.Mask" "F.Paste")
			(net "P5E_CPU1_P0_TX_C_DN<15>")
		)
		(pad "2" smd rect
			(at 0.2667 0)
			(size 0.3048 0.381)
			(layers "F.Cu" "F.Mask" "F.Paste")
			(net "P5E_CPU1_P0_TX_DN<15>")
		)
	)
	(footprint ""
		(layer "F.Cu")
		(at 414.337246 -360.7943)
		(property "Reference" "R8458"
			(at 0 0 0)
			(layer "F.SilkS")
			(hide yes)
			(effects
				(font
					(size 1.27 1.27)
				)
			)
		)
		(property "Value" ""
			(at 0 0 0)
			(layer "F.Fab")
			(effects
				(font
					(size 1.27 1.27)
				)
			)
		)
		(duplicate_pad_numbers_are_jumpers no)
		(fp_line
			(start -0.7874 -0.4064)
			(end 0.7874 -0.4064)
			(stroke
				(width 0.1524)
				(type default)
			)
			(layer "F.SilkS")
		)
		(fp_line
			(start -0.7874 0.4064)
			(end -0.7874 -0.4064)
			(stroke
				(width 0.1524)
				(type default)
			)
			(layer "F.SilkS")
		)
		(fp_line
			(start 0.7874 -0.4064)
			(end 0.7874 0.4064)
			(stroke
				(width 0.1524)
				(type default)
			)
			(layer "F.SilkS")
		)
		(fp_line
			(start 0.7874 0.4064)
			(end -0.7874 0.4064)
			(stroke
				(width 0.1524)
				(type default)
			)
			(layer "F.SilkS")
		)
		(fp_line
			(start -0.67945 -0.305054)
			(end -0.12065 -0.305054)
			(stroke
				(width 0.1)
				(type default)
			)
			(layer "F.Fab")
		)
		(fp_line
			(start -0.67945 0.3048)
			(end -0.67945 -0.305054)
			(stroke
				(width 0.1)
				(type default)
			)
			(layer "F.Fab")
		)
		(fp_line
			(start -0.12065 -0.305054)
			(end -0.12065 -0.2794)
			(stroke
				(width 0.1)
				(type default)
			)
			(layer "F.Fab")
		)
		(fp_line
			(start -0.12065 -0.2794)
			(end 0.12065 -0.2794)
			(stroke
				(width 0.1)
				(type default)
			)
			(layer "F.Fab")
		)
		(fp_line
			(start -0.12065 0.2794)
			(end -0.12065 0.3048)
			(stroke
				(width 0.1)
				(type default)
			)
			(layer "F.Fab")
		)
		(fp_line
			(start -0.12065 0.3048)
			(end -0.67945 0.3048)
			(stroke
				(width 0.1)
				(type default)
			)
			(layer "F.Fab")
		)
		(fp_line
			(start 0.120396 0.2794)
			(end -0.12065 0.2794)
			(stroke
				(width 0.1)
				(type default)
			)
			(layer "F.Fab")
		)
		(fp_line
			(start 0.120396 0.3048)
			(end 0.120396 0.2794)
			(stroke
				(width 0.1)
				(type default)
			)
			(layer "F.Fab")
		)
		(fp_line
			(start 0.12065 -0.3048)
			(end 0.67945 -0.3048)
			(stroke
				(width 0.1)
				(type default)
			)
			(layer "F.Fab")
		)
		(fp_line
			(start 0.12065 -0.2794)
			(end 0.12065 -0.3048)
			(stroke
				(width 0.1)
				(type default)
			)
			(layer "F.Fab")
		)
		(fp_line
			(start 0.67945 -0.3048)
			(end 0.67945 0.3048)
			(stroke
				(width 0.1)
				(type default)
			)
			(layer "F.Fab")
		)
		(fp_line
			(start 0.67945 0.3048)
			(end 0.120396 0.3048)
			(stroke
				(width 0.1)
				(type default)
			)
			(layer "F.Fab")
		)
		(pad "1" smd circle
			(at -0.40005 0)
			(size 0 0)
			(layers "F.Cu" "F.Mask" "F.Paste")
			(net "P3V3_AUX")
		)
		(pad "2" smd circle
			(at 0.40005 0)
			(size 0 0)
			(layers "F.Cu" "F.Mask" "F.Paste")
			(net "PVDD11_S3_P0_VDDIO")
		)
	)
)
